(kicad_pcb
	(version 20241229)
	(generator "pcbnew")
	(generator_version "9.0")
	(general
		(thickness 1.6296)
		(legacy_teardrops no)
	)
	(paper "A3")
	(title_block
		(title "Thunderbolt to 10GbE adapter")
		(date "2026-04-21")
		(rev "1.1.0")
		(company "Antmicro Ltd")
		(comment 1 "www.antmicro.com")
		(comment 9 "footprints 478-482 of 703")
	)
	(layers
		(0 "F.Cu" signal)
		(4 "In1.Cu" signal)
		(6 "In2.Cu" signal)
		(8 "In3.Cu" signal)
		(10 "In4.Cu" signal)
		(12 "In5.Cu" signal)
		(14 "In6.Cu" signal)
		(2 "B.Cu" signal)
		(9 "F.Adhes" user "F.Adhesive")
		(11 "B.Adhes" user "B.Adhesive")
		(13 "F.Paste" user)
		(15 "B.Paste" user)
		(5 "F.SilkS" user "F.Silkscreen")
		(7 "B.SilkS" user "B.Silkscreen")
		(1 "F.Mask" user)
		(3 "B.Mask" user)
		(17 "Dwgs.User" user "User.Drawings")
		(19 "Cmts.User" user "User.Comments")
		(21 "Eco1.User" user "User.Eco1")
		(23 "Eco2.User" user "User.Eco2")
		(25 "Edge.Cuts" user)
		(27 "Margin" user)
		(31 "F.CrtYd" user "F.Courtyard")
		(29 "B.CrtYd" user "B.Courtyard")
		(35 "F.Fab" user)
		(33 "B.Fab" user)
	)
	(footprint "antmicro-footprints:C_0402_1005Metric"
		(layer "B.Cu")
		(at 148.431866 86.935117 180)
		(descr "Capacitor SMD 0402")
		(tags "capacitor SMD 0402")
		(property "Reference" "C253"
			(at -17.975 -9.475 0)
			(layer "B.SilkS")
			(effects
				(font
					(size 0.7 0.7)
					(thickness 0.15)
				)
				(justify mirror)
			)
		)
		(property "Value" "C_1u_25V_0402"
			(at -1.022927 -2.155213 0)
			(layer "B.Fab")
			(effects
				(font
					(size 0.7 0.7)
					(thickness 0.15)
				)
				(justify left bottom mirror)
			)
		)
		(property "Datasheet" "https://www.murata.com/products/productdetail?partno=GRM155R61E105KE11%23"
			(at 0 0 0)
			(layer "B.Fab")
			(hide yes)
			(effects
				(font
					(size 1.27 1.27)
					(thickness 0.15)
				)
				(justify mirror)
			)
		)
		(property "Description" "SMD Multilayer Ceramic Capacitor, 1 µF, 25 V, 0402 [1005 Metric], ± 10%, X5R, GRM Series"
			(at 0 0 0)
			(layer "B.Fab")
			(hide yes)
			(effects
				(font
					(size 1.27 1.27)
					(thickness 0.15)
				)
				(justify mirror)
			)
		)
		(property "MPN" "GRM155R61E105KE11J"
			(at 0 0 180)
			(unlocked yes)
			(layer "B.Fab")
			(hide yes)
			(effects
				(font
					(size 1 1)
					(thickness 0.15)
				)
				(justify mirror)
			)
		)
		(property "Manufacturer" "Murata"
			(at 0 0 180)
			(unlocked yes)
			(layer "B.Fab")
			(hide yes)
			(effects
				(font
					(size 1 1)
					(thickness 0.15)
				)
				(justify mirror)
			)
		)
		(property "License" "Apache-2.0"
			(at 0 0 180)
			(unlocked yes)
			(layer "B.Fab")
			(hide yes)
			(effects
				(font
					(size 1 1)
					(thickness 0.15)
				)
				(justify mirror)
			)
		)
		(property "Author" "Antmicro"
			(at 0 0 180)
			(unlocked yes)
			(layer "B.Fab")
			(hide yes)
			(effects
				(font
					(size 1 1)
					(thickness 0.15)
				)
				(justify mirror)
			)
		)
		(property "Val" "1u"
			(at 0 0 180)
			(unlocked yes)
			(layer "B.Fab")
			(hide yes)
			(effects
				(font
					(size 1 1)
					(thickness 0.15)
				)
				(justify mirror)
			)
		)
		(property "Voltage" "25V"
			(at 0 0 180)
			(unlocked yes)
			(layer "B.Fab")
			(hide yes)
			(effects
				(font
					(size 1 1)
					(thickness 0.15)
				)
				(justify mirror)
			)
		)
		(property "Dielectric" "X5R"
			(at 0 0 180)
			(unlocked yes)
			(layer "B.Fab")
			(hide yes)
			(effects
				(font
					(size 1 1)
					(thickness 0.15)
				)
				(justify mirror)
			)
		)
		(sheetname "/X710-AT2 power/")
		(sheetfile "x710-at2-power.kicad_sch")
		(attr smd)
		(fp_rect
			(start -0.925 0.47)
			(end 0.925 -0.47)
			(stroke
				(width 0.05)
				(type default)
			)
			(fill no)
			(layer "B.CrtYd")
		)
		(fp_line
			(start 0.504 0.25)
			(end 0.504 -0.248)
			(stroke
				(width 0.15)
				(type solid)
			)
			(layer "B.Fab")
		)
		(fp_line
			(start 0.504 -0.248)
			(end -0.494 -0.248)
			(stroke
				(width 0.15)
				(type solid)
			)
			(layer "B.Fab")
		)
		(fp_line
			(start -0.494 0.25)
			(end 0.504 0.25)
			(stroke
				(width 0.15)
				(type solid)
			)
			(layer "B.Fab")
		)
		(fp_line
			(start -0.494 -0.248)
			(end -0.494 0.25)
			(stroke
				(width 0.15)
				(type solid)
			)
			(layer "B.Fab")
		)
		(fp_text user "${REFERENCE}"
			(at -0.939 -4.599 0)
			(layer "B.Fab")
			(effects
				(font
					(size 0.7 0.7)
					(thickness 0.15)
				)
				(justify left bottom mirror)
			)
		)
		(fp_text user "Author: Antmicro"
			(at -0.939 -3.399 0)
			(layer "B.Fab")
			(effects
				(font
					(size 0.7 0.7)
					(thickness 0.15)
				)
				(justify left bottom mirror)
			)
		)
		(fp_text user "License: Apache-2.0"
			(at -0.939 -5.799 0)
			(layer "B.Fab")
			(effects
				(font
					(size 0.7 0.7)
					(thickness 0.15)
				)
				(justify left bottom mirror)
			)
		)
		(pad "1" smd roundrect
			(at -0.48 0 180)
			(size 0.59 0.64)
			(layers "B.Cu" "B.Mask" "B.Paste")
			(roundrect_rratio 0.25)
			(net 23 "GND")
			(pintype "passive")
		)
		(pad "2" smd roundrect
			(at 0.48 0 180)
			(size 0.59 0.64)
			(layers "B.Cu" "B.Mask" "B.Paste")
			(roundrect_rratio 0.25)
			(net 7 "+3V3")
			(pintype "passive")
		)
	)
	(footprint "antmicro-footprints:R_0402_1005Metric"
		(layer "B.Cu")
		(at 174.58 146.66 90)
		(descr "Resistor SMD 0402")
		(tags "resistor SMD 0402")
		(property "Reference" "R214"
			(at -1.09 0.42 270)
			(layer "B.SilkS")
			(effects
				(font
					(size 0.7 0.7)
					(thickness 0.15)
				)
				(justify left bottom mirror)
			)
		)
		(property "Value" "R_220R_0402"
			(at -1.011843 -1.772047 270)
			(layer "B.Fab")
			(effects
				(font
					(size 0.7 0.7)
					(thickness 0.15)
				)
				(justify left bottom mirror)
			)
		)
		(property "Datasheet" "https://www.bourns.com/docs/product-datasheets/cr.pdf"
			(at 0 0 270)
			(layer "B.Fab")
			(hide yes)
			(effects
				(font
					(size 1.27 1.27)
					(thickness 0.15)
				)
				(justify mirror)
			)
		)
		(property "Description" "SMD Chip Resistor, 220 ohm, ± 1%, 62.5 mW, 0402 [1005 Metric], Thick Film, General Purpose"
			(at 0 0 270)
			(layer "B.Fab")
			(hide yes)
			(effects
				(font
					(size 1.27 1.27)
					(thickness 0.15)
				)
				(justify mirror)
			)
		)
		(property "MPN" "CR0402-FX-2200GLF"
			(at 0 0 90)
			(unlocked yes)
			(layer "B.Fab")
			(hide yes)
			(effects
				(font
					(size 1 1)
					(thickness 0.15)
				)
				(justify mirror)
			)
		)
		(property "Manufacturer" "Bourns"
			(at 0 0 90)
			(unlocked yes)
			(layer "B.Fab")
			(hide yes)
			(effects
				(font
					(size 1 1)
					(thickness 0.15)
				)
				(justify mirror)
			)
		)
		(property "License" "Apache-2.0"
			(at 0 0 90)
			(unlocked yes)
			(layer "B.Fab")
			(hide yes)
			(effects
				(font
					(size 1 1)
					(thickness 0.15)
				)
				(justify mirror)
			)
		)
		(property "Author" "Antmicro"
			(at 0 0 90)
			(unlocked yes)
			(layer "B.Fab")
			(hide yes)
			(effects
				(font
					(size 1 1)
					(thickness 0.15)
				)
				(justify mirror)
			)
		)
		(property "Val" "220R"
			(at 0 0 90)
			(unlocked yes)
			(layer "B.Fab")
			(hide yes)
			(effects
				(font
					(size 1 1)
					(thickness 0.15)
				)
				(justify mirror)
			)
		)
		(property "Tolerance" "1%"
			(at 0 0 90)
			(unlocked yes)
			(layer "B.Fab")
			(hide yes)
			(effects
				(font
					(size 1 1)
					(thickness 0.15)
				)
				(justify mirror)
			)
		)
		(sheetname "/2xRJ45/")
		(sheetfile "2xrj45.kicad_sch")
		(attr smd)
		(fp_rect
			(start -0.925 0.47)
			(end 0.925 -0.47)
			(stroke
				(width 0.05)
				(type default)
			)
			(fill no)
			(layer "B.CrtYd")
		)
		(fp_rect
			(start -0.5 0.25)
			(end 0.5 -0.25)
			(stroke
				(width 0.15)
				(type solid)
			)
			(fill no)
			(layer "B.Fab")
		)
		(fp_text user "Author: Antmicro"
			(at -0.95 -4.169 270)
			(layer "B.Fab")
			(effects
				(font
					(size 0.7 0.7)
					(thickness 0.15)
				)
				(justify left bottom mirror)
			)
		)
		(fp_text user "${REFERENCE}"
			(at -0.95 -3.168 270)
			(layer "B.Fab")
			(effects
				(font
					(size 0.7 0.7)
					(thickness 0.15)
				)
				(justify left bottom mirror)
			)
		)
		(fp_text user "License: Apache-2.0"
			(at -0.95 -5.169 270)
			(layer "B.Fab")
			(effects
				(font
					(size 0.7 0.7)
					(thickness 0.15)
				)
				(justify left bottom mirror)
			)
		)
		(pad "1" smd roundrect
			(at -0.48 0 90)
			(size 0.59 0.64)
			(layers "B.Cu" "B.Mask" "B.Paste")
			(roundrect_rratio 0.25)
			(net 409 "Net-(J4-LED_YG_G-)")
			(pintype "passive")
		)
		(pad "2" smd roundrect
			(at 0.48 0 90)
			(size 0.59 0.64)
			(layers "B.Cu" "B.Mask" "B.Paste")
			(roundrect_rratio 0.25)
			(net 66 "/2xRJ45/~{P1_LED_LINK_10G}")
			(pintype "passive")
		)
	)
	(footprint "antmicro-footprints:R_0402_1005Metric"
		(layer "B.Cu")
		(at 152.131866 70.035117 90)
		(descr "Resistor SMD 0402")
		(tags "resistor SMD 0402")
		(property "Reference" "R194"
			(at -9.464883 19.468134 270)
			(layer "B.SilkS")
			(effects
				(font
					(size 0.7 0.7)
					(thickness 0.15)
				)
				(justify mirror)
			)
		)
		(property "Value" "R_3k3_0402"
			(at -1.011843 -1.772047 270)
			(layer "B.Fab")
			(effects
				(font
					(size 0.7 0.7)
					(thickness 0.15)
				)
				(justify left bottom mirror)
			)
		)
		(property "Datasheet" "https://www.bourns.com/docs/product-datasheets/cr.pdf"
			(at 0 0 270)
			(layer "B.Fab")
			(hide yes)
			(effects
				(font
					(size 1.27 1.27)
					(thickness 0.15)
				)
				(justify mirror)
			)
		)
		(property "Description" "SMD Chip Resistor, 3.3 kohm, ± 1%, 63 mW, 0402 [1005 Metric], Thick Film, General Purpose"
			(at 0 0 270)
			(layer "B.Fab")
			(hide yes)
			(effects
				(font
					(size 1.27 1.27)
					(thickness 0.15)
				)
				(justify mirror)
			)
		)
		(property "MPN" "CR0402-FX-3301GLF"
			(at 0 0 90)
			(unlocked yes)
			(layer "B.Fab")
			(hide yes)
			(effects
				(font
					(size 1 1)
					(thickness 0.15)
				)
				(justify mirror)
			)
		)
		(property "Manufacturer" "Bourns"
			(at 0 0 90)
			(unlocked yes)
			(layer "B.Fab")
			(hide yes)
			(effects
				(font
					(size 1 1)
					(thickness 0.15)
				)
				(justify mirror)
			)
		)
		(property "License" "Apache-2.0"
			(at 0 0 90)
			(unlocked yes)
			(layer "B.Fab")
			(hide yes)
			(effects
				(font
					(size 1 1)
					(thickness 0.15)
				)
				(justify mirror)
			)
		)
		(property "Author" "Antmicro"
			(at 0 0 90)
			(unlocked yes)
			(layer "B.Fab")
			(hide yes)
			(effects
				(font
					(size 1 1)
					(thickness 0.15)
				)
				(justify mirror)
			)
		)
		(property "Val" "3k3"
			(at 0 0 90)
			(unlocked yes)
			(layer "B.Fab")
			(hide yes)
			(effects
				(font
					(size 1 1)
					(thickness 0.15)
				)
				(justify mirror)
			)
		)
		(property "Tolerance" "1%"
			(at 0 0 90)
			(unlocked yes)
			(layer "B.Fab")
			(hide yes)
			(effects
				(font
					(size 1 1)
					(thickness 0.15)
				)
				(justify mirror)
			)
		)
		(sheetname "/X710-AT2 10GbE/")
		(sheetfile "x710-at2-10gbe.kicad_sch")
		(attr smd)
		(fp_rect
			(start -0.925 0.47)
			(end 0.925 -0.47)
			(stroke
				(width 0.05)
				(type default)
			)
			(fill no)
			(layer "B.CrtYd")
		)
		(fp_rect
			(start -0.5 0.25)
			(end 0.5 -0.25)
			(stroke
				(width 0.15)
				(type solid)
			)
			(fill no)
			(layer "B.Fab")
		)
		(fp_text user "Author: Antmicro"
			(at -0.95 -4.169 270)
			(layer "B.Fab")
			(effects
				(font
					(size 0.7 0.7)
					(thickness 0.15)
				)
				(justify left bottom mirror)
			)
		)
		(fp_text user "License: Apache-2.0"
			(at -0.95 -5.169 270)
			(layer "B.Fab")
			(effects
				(font
					(size 0.7 0.7)
					(thickness 0.15)
				)
				(justify left bottom mirror)
			)
		)
		(fp_text user "${REFERENCE}"
			(at -0.95 -3.168 270)
			(layer "B.Fab")
			(effects
				(font
					(size 0.7 0.7)
					(thickness 0.15)
				)
				(justify left bottom mirror)
			)
		)
		(pad "1" smd roundrect
			(at -0.48 0 90)
			(size 0.59 0.64)
			(layers "B.Cu" "B.Mask" "B.Paste")
			(roundrect_rratio 0.25)
			(net 76 "/X710-AT2 10GbE/MDIO2_SDA2")
			(pintype "passive")
		)
		(pad "2" smd roundrect
			(at 0.48 0 90)
			(size 0.59 0.64)
			(layers "B.Cu" "B.Mask" "B.Paste")
			(roundrect_rratio 0.25)
			(net 7 "+3V3")
			(pintype "passive")
		)
	)
	(footprint "antmicro-footprints:TP_SMD_0.75mm"
		(layer "B.Cu")
		(at 159.731866 65.935117 90)
		(property "Reference" "TP24"
			(at -0.064883 3.268134 180)
			(layer "B.SilkS")
			(effects
				(font
					(size 0.7 0.7)
					(thickness 0.15)
				)
				(justify left bottom mirror)
			)
		)
		(property "Value" "TP_0.75mm_SMD"
			(at 0 -1.2 270)
			(layer "B.Fab")
			(effects
				(font
					(size 0.7 0.7)
					(thickness 0.15)
				)
				(justify left bottom mirror)
			)
		)
		(property "Description" "SMT test point"
			(at 0 0 270)
			(layer "B.Fab")
			(hide yes)
			(effects
				(font
					(size 1.27 1.27)
					(thickness 0.15)
				)
				(justify mirror)
			)
		)
		(property "MPN" ""
			(at 0 0 90)
			(unlocked yes)
			(layer "B.Fab")
			(hide yes)
			(effects
				(font
					(size 1 1)
					(thickness 0.15)
				)
				(justify mirror)
			)
		)
		(property "Manufacturer" ""
			(at 0 0 90)
			(unlocked yes)
			(layer "B.Fab")
			(hide yes)
			(effects
				(font
					(size 1 1)
					(thickness 0.15)
				)
				(justify mirror)
			)
		)
		(property "Author" "Antmicro"
			(at 0 0 90)
			(unlocked yes)
			(layer "B.Fab")
			(hide yes)
			(effects
				(font
					(size 1 1)
					(thickness 0.15)
				)
				(justify mirror)
			)
		)
		(property "License" "Apache-2.0"
			(at 0 0 90)
			(unlocked yes)
			(layer "B.Fab")
			(hide yes)
			(effects
				(font
					(size 1 1)
					(thickness 0.15)
				)
				(justify mirror)
			)
		)
		(sheetname "/X710-AT2 Misc/")
		(sheetfile "x710-at2-mics.kicad_sch")
		(attr exclude_from_pos_files exclude_from_bom)
		(fp_circle
			(center 0 0)
			(end 0.475 0)
			(stroke
				(width 0.05)
				(type default)
			)
			(fill no)
			(layer "B.CrtYd")
		)
		(fp_text user "License: Apache-2.0"
			(at -0.4 -5.101 270)
			(layer "B.Fab")
			(effects
				(font
					(size 0.7 0.7)
					(thickness 0.15)
				)
				(justify left bottom mirror)
			)
		)
		(fp_text user "Author: Antmicro"
			(at -0.4 -3.901 270)
			(layer "B.Fab")
			(effects
				(font
					(size 0.7 0.7)
					(thickness 0.15)
				)
				(justify left bottom mirror)
			)
		)
		(fp_text user "${REFERENCE}"
			(at -0.4 -2.7 270)
			(layer "B.Fab")
			(effects
				(font
					(size 0.7 0.7)
					(thickness 0.15)
				)
				(justify left bottom mirror)
			)
		)
		(pad "1" smd circle
			(at 0 0 90)
			(size 0.75 0.75)
			(layers "B.Cu" "B.Mask")
			(net 142 "/X710-AT2 Misc/NCSI.CRS_DV")
			(pinfunction "1")
			(pintype "passive")
		)
	)
	(footprint "antmicro-footprints:SOD-523"
		(layer "B.Cu")
		(at 121.5 81.1)
		(property "Reference" "D13"
			(at 0.9 -0.8 180)
			(layer "B.SilkS")
			(effects
				(font
					(size 0.7 0.7)
					(thickness 0.15)
				)
				(justify left bottom mirror)
			)
		)
		(property "Value" "PESD5Z5_0F"
			(at 0 -1.499 180)
			(layer "B.Fab")
			(effects
				(font
					(size 0.7 0.7)
					(thickness 0.15)
				)
				(justify left bottom mirror)
			)
		)
		(property "Datasheet" "https://assets.nexperia.com/documents/data-sheet/PESD5Z5_0.pdf"
			(at 0 0 180)
			(layer "B.Fab")
			(hide yes)
			(effects
				(font
					(size 1.27 1.27)
					(thickness 0.15)
				)
				(justify mirror)
			)
		)
		(property "Description" "Unidirectional TVS, 30 kV,  SOD-523, 5 V, 89 pF"
			(at 0 0 180)
			(layer "B.Fab")
			(hide yes)
			(effects
				(font
					(size 1.27 1.27)
					(thickness 0.15)
				)
				(justify mirror)
			)
		)
		(property "Manufacturer" "Nexperia"
			(at 0 0 0)
			(unlocked yes)
			(layer "B.Fab")
			(hide yes)
			(effects
				(font
					(size 1 1)
					(thickness 0.15)
				)
				(justify mirror)
			)
		)
		(property "MPN" "PESD5Z5.0F"
			(at 0 0 0)
			(unlocked yes)
			(layer "B.Fab")
			(hide yes)
			(effects
				(font
					(size 1 1)
					(thickness 0.15)
				)
				(justify mirror)
			)
		)
		(property "Author" "Antmicro"
			(at 0 0 0)
			(unlocked yes)
			(layer "B.Fab")
			(hide yes)
			(effects
				(font
					(size 1 1)
					(thickness 0.15)
				)
				(justify mirror)
			)
		)
		(property "License" "Apache-2.0"
			(at 0 0 0)
			(unlocked yes)
			(layer "B.Fab")
			(hide yes)
			(effects
				(font
					(size 1 1)
					(thickness 0.15)
				)
				(justify mirror)
			)
		)
		(sheetname "/Fan controller/")
		(sheetfile "fan-controller.kicad_sch")
		(attr smd)
		(fp_line
			(start -0.35 0.5)
			(end -0.35 -0.5)
			(stroke
				(width 0.15)
				(type solid)
			)
			(layer "B.SilkS")
		)
		(fp_rect
			(start -1 0.6)
			(end 1 -0.6)
			(stroke
				(width 0.05)
				(type solid)
			)
			(fill no)
			(layer "B.CrtYd")
		)
		(fp_line
			(start -0.652 -0.423)
			(end -0.652 0.425)
			(stroke
				(width 0.15)
				(type solid)
			)
			(layer "B.Fab")
		)
		(fp_line
			(start -0.652 -0.423)
			(end 0.65 -0.423)
			(stroke
				(width 0.15)
				(type solid)
			)
			(layer "B.Fab")
		)
		(fp_line
			(start -0.652 0.425)
			(end 0.65 0.425)
			(stroke
				(width 0.15)
				(type solid)
			)
			(layer "B.Fab")
		)
		(fp_line
			(start -0.35 0.4)
			(end -0.35 -0.4)
			(stroke
				(width 0.15)
				(type solid)
			)
			(layer "B.Fab")
		)
		(fp_line
			(start 0.65 0.425)
			(end 0.65 -0.423)
			(stroke
				(width 0.15)
				(type solid)
			)
			(layer "B.Fab")
		)
		(fp_text user "${REFERENCE}"
			(at -1.276 -3.499 180)
			(layer "B.Fab")
			(effects
				(font
					(size 0.7 0.7)
					(thickness 0.15)
				)
				(justify left bottom mirror)
			)
		)
		(fp_text user "License: Apache-2.0"
			(at -1.276 -5.9 180)
			(layer "B.Fab")
			(effects
				(font
					(size 0.7 0.7)
					(thickness 0.15)
				)
				(justify left bottom mirror)
			)
		)
		(fp_text user "Author: Antmicro"
			(at -1.276 -4.7 180)
			(layer "B.Fab")
			(effects
				(font
					(size 0.7 0.7)
					(thickness 0.15)
				)
				(justify left bottom mirror)
			)
		)
		(pad "1" smd roundrect
			(at -0.701 0)
			(size 0.5 0.6)
			(layers "B.Cu" "B.Mask" "B.Paste")
			(roundrect_rratio 0.25)
			(net 40 "+5V")
			(pinfunction "C")
			(pintype "passive")
		)
		(pad "2" smd roundrect
			(at 0.699 0)
			(size 0.5 0.6)
			(layers "B.Cu" "B.Mask" "B.Paste")
			(roundrect_rratio 0.25)
			(net 23 "GND")
			(pinfunction "A")
			(pintype "passive")
		)
	)
)
